(kicad_pcb
	(version 20260206)
	(generator "pcbnew")
	(generator_version "10.0")
	(general
		(thickness 1.6)
		(legacy_teardrops no)
	)
	(paper "A4")
	(title_block
		(title "01162023_DA0F0TEBIF0_F0T_Expander_BD_F_brd_V02_OCP.brd")
		(comment 1 "Grand Teton / footprints 3392-3399 of 9728")
	)
	(layers
		(0 "F.Cu" signal "TOP")
		(4 "In1.Cu" signal "GND")
		(6 "In2.Cu" signal "VCC")
		(8 "In3.Cu" signal "VCC1")
		(10 "In4.Cu" signal "GND1")
		(12 "In5.Cu" signal "IN1")
		(14 "In6.Cu" signal "GND2")
		(16 "In7.Cu" signal "IN2")
		(18 "In8.Cu" signal "GND3")
		(20 "In9.Cu" signal "IN3")
		(22 "In10.Cu" signal "GND4")
		(24 "In11.Cu" signal "IN4")
		(26 "In12.Cu" signal "GND5")
		(28 "In13.Cu" signal "IN5")
		(30 "In14.Cu" signal "GND6")
		(32 "In15.Cu" signal "IN6")
		(34 "In16.Cu" signal "GND7")
		(2 "B.Cu" signal "BOTTOM")
		(9 "F.Adhes" user "F.Adhesive")
		(11 "B.Adhes" user "B.Adhesive")
		(13 "F.Paste" user "Package Geometry/Pastemask Top")
		(15 "B.Paste" user "Package Geometry/Pastemask Bottom")
		(5 "F.SilkS" user "Ref Des/Silkscreen Top")
		(7 "B.SilkS" user "Ref Des/Silkscreen Bottom")
		(1 "F.Mask" user "Board Geometry/Soldermask Top")
		(3 "B.Mask" user "Board Geometry/Soldermask Bottom")
		(17 "Dwgs.User" user "User.Drawings")
		(19 "Cmts.User" user "User.Comments")
		(21 "Eco1.User" user "User.Eco1")
		(23 "Eco2.User" user "User.Eco2")
		(25 "Edge.Cuts" user "Board Geometry/Outline")
		(27 "Margin" user)
		(31 "F.CrtYd" user "Package Geometry/Place Bound Top")
		(29 "B.CrtYd" user "Package Geometry/Place Bound Bottom")
		(35 "F.Fab" user "Ref Des/Assembly Top")
		(33 "B.Fab" user "Ref Des/Assembly Bottom")
	)
	(footprint ""
		(layer "F.Cu")
		(at 43.839892 -70.52437 90)
		(property "Reference" "PC369"
			(at 0 0 90)
			(layer "F.SilkS")
			(hide yes)
			(effects
				(font
					(size 1.27 1.27)
				)
			)
		)
		(property "Value" ""
			(at 0 0 90)
			(layer "F.Fab")
			(effects
				(font
					(size 1.27 1.27)
				)
			)
		)
		(duplicate_pad_numbers_are_jumpers no)
		(fp_line
			(start 1.524 -0.762)
			(end 1.524 0.762)
			(stroke
				(width 0.1524)
				(type default)
			)
			(layer "F.SilkS")
		)
		(fp_line
			(start -1.524 -0.762)
			(end 1.524 -0.762)
			(stroke
				(width 0.1524)
				(type default)
			)
			(layer "F.SilkS")
		)
		(fp_line
			(start 1.524 0.762)
			(end -1.524 0.762)
			(stroke
				(width 0.1524)
				(type default)
			)
			(layer "F.SilkS")
		)
		(fp_line
			(start -1.524 0.762)
			(end -1.524 -0.762)
			(stroke
				(width 0.1524)
				(type default)
			)
			(layer "F.SilkS")
		)
		(fp_line
			(start 1.1049 -0.724916)
			(end -1.1049 -0.724916)
			(stroke
				(width 0.1)
				(type default)
			)
			(layer "F.Fab")
		)
		(fp_line
			(start -1.1049 -0.724916)
			(end -1.1049 0.724916)
			(stroke
				(width 0.1)
				(type default)
			)
			(layer "F.Fab")
		)
		(fp_line
			(start 1.1049 0.724916)
			(end 1.1049 -0.724916)
			(stroke
				(width 0.1)
				(type default)
			)
			(layer "F.Fab")
		)
		(fp_line
			(start -1.1049 0.724916)
			(end 1.1049 0.724916)
			(stroke
				(width 0.1)
				(type default)
			)
			(layer "F.Fab")
		)
		(pad "1" smd rect
			(at -0.889 0 270)
			(size 1.016 1.27)
			(layers "F.Cu" "F.Mask" "F.Paste")
			(net "P12V_SSD1_R")
		)
		(pad "2" smd rect
			(at 0.889 0 270)
			(size 1.016 1.27)
			(layers "F.Cu" "F.Mask" "F.Paste")
			(net "GND")
		)
	)
	(footprint ""
		(layer "F.Cu")
		(at 170.975274 -63.086234)
		(property "Reference" "R5988"
			(at 0 0 0)
			(layer "F.SilkS")
			(hide yes)
			(effects
				(font
					(size 1.27 1.27)
				)
			)
		)
		(property "Value" ""
			(at 0 0 0)
			(layer "F.Fab")
			(effects
				(font
					(size 1.27 1.27)
				)
			)
		)
		(duplicate_pad_numbers_are_jumpers no)
		(fp_line
			(start -0.7874 -0.4064)
			(end 0.7874 -0.4064)
			(stroke
				(width 0.1524)
				(type default)
			)
			(layer "F.SilkS")
		)
		(fp_line
			(start -0.7874 0.4064)
			(end -0.7874 -0.4064)
			(stroke
				(width 0.1524)
				(type default)
			)
			(layer "F.SilkS")
		)
		(fp_line
			(start 0.7874 -0.4064)
			(end 0.7874 0.4064)
			(stroke
				(width 0.1524)
				(type default)
			)
			(layer "F.SilkS")
		)
		(fp_line
			(start 0.7874 0.4064)
			(end -0.7874 0.4064)
			(stroke
				(width 0.1524)
				(type default)
			)
			(layer "F.SilkS")
		)
		(fp_line
			(start -0.67945 -0.305054)
			(end -0.12065 -0.305054)
			(stroke
				(width 0.1)
				(type default)
			)
			(layer "F.Fab")
		)
		(fp_line
			(start -0.67945 0.3048)
			(end -0.67945 -0.305054)
			(stroke
				(width 0.1)
				(type default)
			)
			(layer "F.Fab")
		)
		(fp_line
			(start -0.12065 -0.305054)
			(end -0.12065 -0.2794)
			(stroke
				(width 0.1)
				(type default)
			)
			(layer "F.Fab")
		)
		(fp_line
			(start -0.12065 -0.2794)
			(end 0.12065 -0.2794)
			(stroke
				(width 0.1)
				(type default)
			)
			(layer "F.Fab")
		)
		(fp_line
			(start -0.12065 0.2794)
			(end -0.12065 0.3048)
			(stroke
				(width 0.1)
				(type default)
			)
			(layer "F.Fab")
		)
		(fp_line
			(start -0.12065 0.3048)
			(end -0.67945 0.3048)
			(stroke
				(width 0.1)
				(type default)
			)
			(layer "F.Fab")
		)
		(fp_line
			(start 0.120396 0.2794)
			(end -0.12065 0.2794)
			(stroke
				(width 0.1)
				(type default)
			)
			(layer "F.Fab")
		)
		(fp_line
			(start 0.120396 0.3048)
			(end 0.120396 0.2794)
			(stroke
				(width 0.1)
				(type default)
			)
			(layer "F.Fab")
		)
		(fp_line
			(start 0.12065 -0.3048)
			(end 0.67945 -0.3048)
			(stroke
				(width 0.1)
				(type default)
			)
			(layer "F.Fab")
		)
		(fp_line
			(start 0.12065 -0.2794)
			(end 0.12065 -0.3048)
			(stroke
				(width 0.1)
				(type default)
			)
			(layer "F.Fab")
		)
		(fp_line
			(start 0.67945 -0.3048)
			(end 0.67945 0.3048)
			(stroke
				(width 0.1)
				(type default)
			)
			(layer "F.Fab")
		)
		(fp_line
			(start 0.67945 0.3048)
			(end 0.120396 0.3048)
			(stroke
				(width 0.1)
				(type default)
			)
			(layer "F.Fab")
		)
		(pad "1" smd circle
			(at -0.40005 0)
			(size 0 0)
			(layers "F.Cu" "F.Mask" "F.Paste")
			(net "P12V_SSD6_R")
		)
		(pad "2" smd circle
			(at 0.40005 0)
			(size 0 0)
			(layers "F.Cu" "F.Mask" "F.Paste")
			(net "P12V_SSD6_PG_G1")
		)
	)
	(footprint ""
		(layer "F.Cu")
		(at 375.230136 -281.203908 -90)
		(property "Reference" "C3585"
			(at 0 0 270)
			(layer "F.SilkS")
			(hide yes)
			(effects
				(font
					(size 1.27 1.27)
				)
			)
		)
		(property "Value" ""
			(at 0 0 270)
			(layer "F.Fab")
			(effects
				(font
					(size 1.27 1.27)
				)
			)
		)
		(duplicate_pad_numbers_are_jumpers no)
		(fp_line
			(start -1.2954 0.5842)
			(end -1.2954 -0.5842)
			(stroke
				(width 0.1524)
				(type default)
			)
			(layer "F.SilkS")
		)
		(fp_line
			(start 1.2954 0.5842)
			(end -1.2954 0.5842)
			(stroke
				(width 0.1524)
				(type default)
			)
			(layer "F.SilkS")
		)
		(fp_line
			(start -1.2954 -0.5842)
			(end 1.2954 -0.5842)
			(stroke
				(width 0.1524)
				(type default)
			)
			(layer "F.SilkS")
		)
		(fp_line
			(start 1.2954 -0.5842)
			(end 1.2954 0.5842)
			(stroke
				(width 0.1524)
				(type default)
			)
			(layer "F.SilkS")
		)
		(fp_line
			(start -0.8636 0.4572)
			(end -0.8636 0.4064)
			(stroke
				(width 0.1)
				(type default)
			)
			(layer "F.Fab")
		)
		(fp_line
			(start 0.8636 0.4572)
			(end -0.8636 0.4572)
			(stroke
				(width 0.1)
				(type default)
			)
			(layer "F.Fab")
		)
		(fp_line
			(start -1.1938 0.4064)
			(end -1.1938 -0.4064)
			(stroke
				(width 0.1)
				(type default)
			)
			(layer "F.Fab")
		)
		(fp_line
			(start -0.8636 0.4064)
			(end -1.1938 0.4064)
			(stroke
				(width 0.1)
				(type default)
			)
			(layer "F.Fab")
		)
		(fp_line
			(start 0.8636 0.4064)
			(end 0.8636 0.4572)
			(stroke
				(width 0.1)
				(type default)
			)
			(layer "F.Fab")
		)
		(fp_line
			(start 1.1938 0.4064)
			(end 0.8636 0.4064)
			(stroke
				(width 0.1)
				(type default)
			)
			(layer "F.Fab")
		)
		(fp_line
			(start -1.1938 -0.4064)
			(end -0.8636 -0.4064)
			(stroke
				(width 0.1)
				(type default)
			)
			(layer "F.Fab")
		)
		(fp_line
			(start -0.8636 -0.4064)
			(end -0.8636 -0.4572)
			(stroke
				(width 0.1)
				(type default)
			)
			(layer "F.Fab")
		)
		(fp_line
			(start 0.8636 -0.4064)
			(end 1.1938 -0.4064)
			(stroke
				(width 0.1)
				(type default)
			)
			(layer "F.Fab")
		)
		(fp_line
			(start 1.1938 -0.4064)
			(end 1.1938 0.4064)
			(stroke
				(width 0.1)
				(type default)
			)
			(layer "F.Fab")
		)
		(fp_line
			(start -0.8636 -0.4572)
			(end 0.8636 -0.4572)
			(stroke
				(width 0.1)
				(type default)
			)
			(layer "F.Fab")
		)
		(fp_line
			(start 0.8636 -0.4572)
			(end 0.8636 -0.4064)
			(stroke
				(width 0.1)
				(type default)
			)
			(layer "F.Fab")
		)
		(pad "1" smd rect
			(at -0.7366 0 180)
			(size 0.7112 0.8128)
			(layers "F.Cu" "F.Mask" "F.Paste")
			(net "P1V8_PLL0_PEX3")
		)
		(pad "2" smd rect
			(at 0.7366 0 180)
			(size 0.7112 0.8128)
			(layers "F.Cu" "F.Mask" "F.Paste")
			(net "GND")
		)
	)
	(footprint ""
		(layer "F.Cu")
		(at 117.958362 -128.947926)
		(property "Reference" "PC302"
			(at 0 0 0)
			(layer "F.SilkS")
			(hide yes)
			(effects
				(font
					(size 1.27 1.27)
				)
			)
		)
		(property "Value" ""
			(at 0 0 0)
			(layer "F.Fab")
			(effects
				(font
					(size 1.27 1.27)
				)
			)
		)
		(duplicate_pad_numbers_are_jumpers no)
		(fp_line
			(start -0.7874 -0.4064)
			(end 0.7874 -0.4064)
			(stroke
				(width 0.1524)
				(type default)
			)
			(layer "F.SilkS")
		)
		(fp_line
			(start -0.7874 0.4064)
			(end -0.7874 -0.4064)
			(stroke
				(width 0.1524)
				(type default)
			)
			(layer "F.SilkS")
		)
		(fp_line
			(start 0.7874 -0.4064)
			(end 0.7874 0.4064)
			(stroke
				(width 0.1524)
				(type default)
			)
			(layer "F.SilkS")
		)
		(fp_line
			(start 0.7874 0.4064)
			(end -0.7874 0.4064)
			(stroke
				(width 0.1524)
				(type default)
			)
			(layer "F.SilkS")
		)
		(fp_line
			(start -0.67945 -0.305054)
			(end -0.12065 -0.305054)
			(stroke
				(width 0.1)
				(type default)
			)
			(layer "F.Fab")
		)
		(fp_line
			(start -0.67945 0.3048)
			(end -0.67945 -0.305054)
			(stroke
				(width 0.1)
				(type default)
			)
			(layer "F.Fab")
		)
		(fp_line
			(start -0.12065 -0.305054)
			(end -0.12065 -0.2794)
			(stroke
				(width 0.1)
				(type default)
			)
			(layer "F.Fab")
		)
		(fp_line
			(start -0.12065 -0.2794)
			(end 0.12065 -0.2794)
			(stroke
				(width 0.1)
				(type default)
			)
			(layer "F.Fab")
		)
		(fp_line
			(start -0.12065 0.2794)
			(end -0.12065 0.3048)
			(stroke
				(width 0.1)
				(type default)
			)
			(layer "F.Fab")
		)
		(fp_line
			(start -0.12065 0.3048)
			(end -0.67945 0.3048)
			(stroke
				(width 0.1)
				(type default)
			)
			(layer "F.Fab")
		)
		(fp_line
			(start 0.120396 0.2794)
			(end -0.12065 0.2794)
			(stroke
				(width 0.1)
				(type default)
			)
			(layer "F.Fab")
		)
		(fp_line
			(start 0.120396 0.3048)
			(end 0.120396 0.2794)
			(stroke
				(width 0.1)
				(type default)
			)
			(layer "F.Fab")
		)
		(fp_line
			(start 0.12065 -0.3048)
			(end 0.67945 -0.3048)
			(stroke
				(width 0.1)
				(type default)
			)
			(layer "F.Fab")
		)
		(fp_line
			(start 0.12065 -0.2794)
			(end 0.12065 -0.3048)
			(stroke
				(width 0.1)
				(type default)
			)
			(layer "F.Fab")
		)
		(fp_line
			(start 0.67945 -0.3048)
			(end 0.67945 0.3048)
			(stroke
				(width 0.1)
				(type default)
			)
			(layer "F.Fab")
		)
		(fp_line
			(start 0.67945 0.3048)
			(end 0.120396 0.3048)
			(stroke
				(width 0.1)
				(type default)
			)
			(layer "F.Fab")
		)
		(pad "1" smd circle
			(at -0.40005 0)
			(size 0 0)
			(layers "F.Cu" "F.Mask" "F.Paste")
			(net "P5V_AUX")
		)
		(pad "2" smd circle
			(at 0.40005 0)
			(size 0 0)
			(layers "F.Cu" "F.Mask" "F.Paste")
			(net "GND")
		)
	)
	(footprint ""
		(layer "F.Cu")
		(at 304.374804 -48.753014 180)
		(property "Reference" "C324"
			(at 0 0 180)
			(layer "F.SilkS")
			(hide yes)
			(effects
				(font
					(size 1.27 1.27)
				)
			)
		)
		(property "Value" ""
			(at 0 0 180)
			(layer "F.Fab")
			(effects
				(font
					(size 1.27 1.27)
				)
			)
		)
		(duplicate_pad_numbers_are_jumpers no)
		(fp_line
			(start 0.7874 0.4064)
			(end -0.7874 0.4064)
			(stroke
				(width 0.1524)
				(type default)
			)
			(layer "F.SilkS")
		)
		(fp_line
			(start 0.7874 -0.4064)
			(end 0.7874 0.4064)
			(stroke
				(width 0.1524)
				(type default)
			)
			(layer "F.SilkS")
		)
		(fp_line
			(start -0.7874 0.4064)
			(end -0.7874 -0.4064)
			(stroke
				(width 0.1524)
				(type default)
			)
			(layer "F.SilkS")
		)
		(fp_line
			(start -0.7874 -0.4064)
			(end 0.7874 -0.4064)
			(stroke
				(width 0.1524)
				(type default)
			)
			(layer "F.SilkS")
		)
		(fp_line
			(start 0.67945 0.3048)
			(end 0.120396 0.3048)
			(stroke
				(width 0.1)
				(type default)
			)
			(layer "F.Fab")
		)
		(fp_line
			(start 0.67945 -0.3048)
			(end 0.67945 0.3048)
			(stroke
				(width 0.1)
				(type default)
			)
			(layer "F.Fab")
		)
		(fp_line
			(start 0.12065 -0.2794)
			(end 0.12065 -0.3048)
			(stroke
				(width 0.1)
				(type default)
			)
			(layer "F.Fab")
		)
		(fp_line
			(start 0.12065 -0.3048)
			(end 0.67945 -0.3048)
			(stroke
				(width 0.1)
				(type default)
			)
			(layer "F.Fab")
		)
		(fp_line
			(start 0.120396 0.3048)
			(end 0.120396 0.2794)
			(stroke
				(width 0.1)
				(type default)
			)
			(layer "F.Fab")
		)
		(fp_line
			(start 0.120396 0.2794)
			(end -0.12065 0.2794)
			(stroke
				(width 0.1)
				(type default)
			)
			(layer "F.Fab")
		)
		(fp_line
			(start -0.12065 0.3048)
			(end -0.67945 0.3048)
			(stroke
				(width 0.1)
				(type default)
			)
			(layer "F.Fab")
		)
		(fp_line
			(start -0.12065 0.2794)
			(end -0.12065 0.3048)
			(stroke
				(width 0.1)
				(type default)
			)
			(layer "F.Fab")
		)
		(fp_line
			(start -0.12065 -0.2794)
			(end 0.12065 -0.2794)
			(stroke
				(width 0.1)
				(type default)
			)
			(layer "F.Fab")
		)
		(fp_line
			(start -0.12065 -0.305054)
			(end -0.12065 -0.2794)
			(stroke
				(width 0.1)
				(type default)
			)
			(layer "F.Fab")
		)
		(fp_line
			(start -0.67945 0.3048)
			(end -0.67945 -0.305054)
			(stroke
				(width 0.1)
				(type default)
			)
			(layer "F.Fab")
		)
		(fp_line
			(start -0.67945 -0.305054)
			(end -0.12065 -0.305054)
			(stroke
				(width 0.1)
				(type default)
			)
			(layer "F.Fab")
		)
		(pad "1" smd circle
			(at -0.40005 0 180)
			(size 0 0)
			(layers "F.Cu" "F.Mask" "F.Paste")
			(net "P3V3_AUX")
		)
		(pad "2" smd circle
			(at 0.40005 0 180)
			(size 0 0)
			(layers "F.Cu" "F.Mask" "F.Paste")
			(net "GND")
		)
	)
	(footprint ""
		(layer "F.Cu")
		(at 289.49396 -34.248852)
		(property "Reference" "R5691"
			(at 0 0 0)
			(layer "F.SilkS")
			(hide yes)
			(effects
				(font
					(size 1.27 1.27)
				)
			)
		)
		(property "Value" ""
			(at 0 0 0)
			(layer "F.Fab")
			(effects
				(font
					(size 1.27 1.27)
				)
			)
		)
		(duplicate_pad_numbers_are_jumpers no)
		(fp_line
			(start -0.7874 -0.4064)
			(end 0.7874 -0.4064)
			(stroke
				(width 0.1524)
				(type default)
			)
			(layer "F.SilkS")
		)
		(fp_line
			(start -0.7874 0.4064)
			(end -0.7874 -0.4064)
			(stroke
				(width 0.1524)
				(type default)
			)
			(layer "F.SilkS")
		)
		(fp_line
			(start 0.7874 -0.4064)
			(end 0.7874 0.4064)
			(stroke
				(width 0.1524)
				(type default)
			)
			(layer "F.SilkS")
		)
		(fp_line
			(start 0.7874 0.4064)
			(end -0.7874 0.4064)
			(stroke
				(width 0.1524)
				(type default)
			)
			(layer "F.SilkS")
		)
		(fp_line
			(start -0.67945 -0.305054)
			(end -0.12065 -0.305054)
			(stroke
				(width 0.1)
				(type default)
			)
			(layer "F.Fab")
		)
		(fp_line
			(start -0.67945 0.3048)
			(end -0.67945 -0.305054)
			(stroke
				(width 0.1)
				(type default)
			)
			(layer "F.Fab")
		)
		(fp_line
			(start -0.12065 -0.305054)
			(end -0.12065 -0.2794)
			(stroke
				(width 0.1)
				(type default)
			)
			(layer "F.Fab")
		)
		(fp_line
			(start -0.12065 -0.2794)
			(end 0.12065 -0.2794)
			(stroke
				(width 0.1)
				(type default)
			)
			(layer "F.Fab")
		)
		(fp_line
			(start -0.12065 0.2794)
			(end -0.12065 0.3048)
			(stroke
				(width 0.1)
				(type default)
			)
			(layer "F.Fab")
		)
		(fp_line
			(start -0.12065 0.3048)
			(end -0.67945 0.3048)
			(stroke
				(width 0.1)
				(type default)
			)
			(layer "F.Fab")
		)
		(fp_line
			(start 0.120396 0.2794)
			(end -0.12065 0.2794)
			(stroke
				(width 0.1)
				(type default)
			)
			(layer "F.Fab")
		)
		(fp_line
			(start 0.120396 0.3048)
			(end 0.120396 0.2794)
			(stroke
				(width 0.1)
				(type default)
			)
			(layer "F.Fab")
		)
		(fp_line
			(start 0.12065 -0.3048)
			(end 0.67945 -0.3048)
			(stroke
				(width 0.1)
				(type default)
			)
			(layer "F.Fab")
		)
		(fp_line
			(start 0.12065 -0.2794)
			(end 0.12065 -0.3048)
			(stroke
				(width 0.1)
				(type default)
			)
			(layer "F.Fab")
		)
		(fp_line
			(start 0.67945 -0.3048)
			(end 0.67945 0.3048)
			(stroke
				(width 0.1)
				(type default)
			)
			(layer "F.Fab")
		)
		(fp_line
			(start 0.67945 0.3048)
			(end 0.120396 0.3048)
			(stroke
				(width 0.1)
				(type default)
			)
			(layer "F.Fab")
		)
		(pad "1" smd circle
			(at -0.40005 0)
			(size 0 0)
			(layers "F.Cu" "F.Mask" "F.Paste")
			(net "RST_SMB_SSD10_ISO_N")
		)
		(pad "2" smd circle
			(at 0.40005 0)
			(size 0 0)
			(layers "F.Cu" "F.Mask" "F.Paste")
			(net "P3V3_SSD10")
		)
	)
	(footprint ""
		(layer "F.Cu")
		(at 114.945668 -350.098614 90)
		(property "Reference" "C342"
			(at 0 0 90)
			(layer "F.SilkS")
			(hide yes)
			(effects
				(font
					(size 1.27 1.27)
				)
			)
		)
		(property "Value" ""
			(at 0 0 90)
			(layer "F.Fab")
			(effects
				(font
					(size 1.27 1.27)
				)
			)
		)
		(duplicate_pad_numbers_are_jumpers no)
		(fp_line
			(start 0.299974 -0.150114)
			(end 0.299974 0.150114)
			(stroke
				(width 0.1)
				(type default)
			)
			(layer "F.Fab")
		)
		(fp_line
			(start -0.299974 -0.150114)
			(end 0.299974 -0.150114)
			(stroke
				(width 0.1)
				(type default)
			)
			(layer "F.Fab")
		)
		(fp_line
			(start 0.299974 0.150114)
			(end -0.299974 0.150114)
			(stroke
				(width 0.1)
				(type default)
			)
			(layer "F.Fab")
		)
		(fp_line
			(start -0.299974 0.150114)
			(end -0.299974 -0.150114)
			(stroke
				(width 0.1)
				(type default)
			)
			(layer "F.Fab")
		)
		(pad "1" smd rect
			(at -0.2667 0 90)
			(size 0.3048 0.381)
			(layers "F.Cu" "F.Mask" "F.Paste")
			(net "P5E_PEX1_STN6_TX_DP<110>")
		)
		(pad "2" smd rect
			(at 0.2667 0 90)
			(size 0.3048 0.381)
			(layers "F.Cu" "F.Mask" "F.Paste")
			(net "P5E_PEX1_STN6_TX_C_DP<110>")
		)
	)
	(footprint ""
		(layer "F.Cu")
		(at 368.734594 -33.631886 180)
		(property "Reference" "C699"
			(at 0 0 180)
			(layer "F.SilkS")
			(hide yes)
			(effects
				(font
					(size 1.27 1.27)
				)
			)
		)
		(property "Value" ""
			(at 0 0 180)
			(layer "F.Fab")
			(effects
				(font
					(size 1.27 1.27)
				)
			)
		)
		(duplicate_pad_numbers_are_jumpers no)
		(fp_line
			(start 0.299974 0.150114)
			(end -0.299974 0.150114)
			(stroke
				(width 0.1)
				(type default)
			)
			(layer "F.Fab")
		)
		(fp_line
			(start 0.299974 -0.150114)
			(end 0.299974 0.150114)
			(stroke
				(width 0.1)
				(type default)
			)
			(layer "F.Fab")
		)
		(fp_line
			(start -0.299974 0.150114)
			(end -0.299974 -0.150114)
			(stroke
				(width 0.1)
				(type default)
			)
			(layer "F.Fab")
		)
		(fp_line
			(start -0.299974 -0.150114)
			(end 0.299974 -0.150114)
			(stroke
				(width 0.1)
				(type default)
			)
			(layer "F.Fab")
		)
		(pad "1" smd rect
			(at -0.2667 0 180)
			(size 0.3048 0.381)
			(layers "F.Cu" "F.Mask" "F.Paste")
			(net "P5E_PEX3_STN2_TX_DN<47>")
		)
		(pad "2" smd rect
			(at 0.2667 0 180)
			(size 0.3048 0.381)
			(layers "F.Cu" "F.Mask" "F.Paste")
			(net "P5E_PEX3_STN2_TX_C_DN<47>")
		)
	)
)
